(kicad_pcb
	(version 20260206)
	(generator "pcbnew")
	(generator_version "10.0")
	(general
		(thickness 1.6)
		(legacy_teardrops no)
	)
	(paper "A4")
	(title_block
		(title "03242023_DA0F0TMBIJ0_F0T_Motherboard_J_brd_V01_OCP.brd")
		(comment 1 "Grand Teton / footprints 5471-5476 of 6105")
	)
	(layers
		(0 "F.Cu" signal "TOP")
		(4 "In1.Cu" signal "GND")
		(6 "In2.Cu" signal "IN1")
		(8 "In3.Cu" signal "GND1")
		(10 "In4.Cu" signal "IN2")
		(12 "In5.Cu" signal "GND2")
		(14 "In6.Cu" signal "IN3")
		(16 "In7.Cu" signal "GND3")
		(18 "In8.Cu" signal "VCC")
		(20 "In9.Cu" signal "VCC1")
		(22 "In10.Cu" signal "GND4")
		(24 "In11.Cu" signal "IN4")
		(26 "In12.Cu" signal "GND5")
		(28 "In13.Cu" signal "IN5")
		(30 "In14.Cu" signal "GND6")
		(32 "In15.Cu" signal "IN6")
		(34 "In16.Cu" signal "GND7")
		(2 "B.Cu" signal "BOTTOM")
		(9 "F.Adhes" user "F.Adhesive")
		(11 "B.Adhes" user "B.Adhesive")
		(13 "F.Paste" user "Package Geometry/Pastemask Top")
		(15 "B.Paste" user "Package Geometry/Pastemask Bottom")
		(5 "F.SilkS" user "Ref Des/Silkscreen Top")
		(7 "B.SilkS" user "Ref Des/Silkscreen Bottom")
		(1 "F.Mask" user "Board Geometry/Soldermask Top")
		(3 "B.Mask" user "Board Geometry/Soldermask Bottom")
		(17 "Dwgs.User" user "User.Drawings")
		(19 "Cmts.User" user "User.Comments")
		(21 "Eco1.User" user "User.Eco1")
		(23 "Eco2.User" user "User.Eco2")
		(25 "Edge.Cuts" user "Board Geometry/Outline")
		(27 "Margin" user)
		(31 "F.CrtYd" user "Package Geometry/Place Bound Top")
		(29 "B.CrtYd" user "Package Geometry/Place Bound Bottom")
		(35 "F.Fab" user "Ref Des/Assembly Top")
		(33 "B.Fab" user "Ref Des/Assembly Bottom")
	)
	(footprint ""
		(layer "B.Cu")
		(at 237.837472 -128.518158 180)
		(property "Reference" "C207"
			(at 0 0 0)
			(layer "B.SilkS")
			(hide yes)
			(effects
				(font
					(size 1.27 1.27)
				)
				(justify mirror)
			)
		)
		(property "Value" ""
			(at 0 0 0)
			(layer "B.Fab")
			(effects
				(font
					(size 1.27 1.27)
				)
				(justify mirror)
			)
		)
		(duplicate_pad_numbers_are_jumpers no)
		(fp_line
			(start 0.7874 0.4064)
			(end 0.7874 -0.4064)
			(stroke
				(width 0.1524)
				(type default)
			)
			(layer "B.SilkS")
		)
		(fp_line
			(start 0.7874 -0.4064)
			(end -0.7874 -0.4064)
			(stroke
				(width 0.1524)
				(type default)
			)
			(layer "B.SilkS")
		)
		(fp_line
			(start -0.7874 0.4064)
			(end 0.7874 0.4064)
			(stroke
				(width 0.1524)
				(type default)
			)
			(layer "B.SilkS")
		)
		(fp_line
			(start -0.7874 -0.4064)
			(end -0.7874 0.4064)
			(stroke
				(width 0.1524)
				(type default)
			)
			(layer "B.SilkS")
		)
		(fp_line
			(start 0.67945 0.3048)
			(end 0.67945 -0.305054)
			(stroke
				(width 0.1)
				(type default)
			)
			(layer "B.Fab")
		)
		(fp_line
			(start 0.67945 -0.305054)
			(end 0.12065 -0.305054)
			(stroke
				(width 0.1)
				(type default)
			)
			(layer "B.Fab")
		)
		(fp_line
			(start 0.12065 0.3048)
			(end 0.67945 0.3048)
			(stroke
				(width 0.1)
				(type default)
			)
			(layer "B.Fab")
		)
		(fp_line
			(start 0.12065 0.2794)
			(end 0.12065 0.3048)
			(stroke
				(width 0.1)
				(type default)
			)
			(layer "B.Fab")
		)
		(fp_line
			(start 0.12065 -0.2794)
			(end -0.12065 -0.2794)
			(stroke
				(width 0.1)
				(type default)
			)
			(layer "B.Fab")
		)
		(fp_line
			(start 0.12065 -0.305054)
			(end 0.12065 -0.2794)
			(stroke
				(width 0.1)
				(type default)
			)
			(layer "B.Fab")
		)
		(fp_line
			(start -0.120396 0.3048)
			(end -0.120396 0.2794)
			(stroke
				(width 0.1)
				(type default)
			)
			(layer "B.Fab")
		)
		(fp_line
			(start -0.120396 0.2794)
			(end 0.12065 0.2794)
			(stroke
				(width 0.1)
				(type default)
			)
			(layer "B.Fab")
		)
		(fp_line
			(start -0.12065 -0.2794)
			(end -0.12065 -0.3048)
			(stroke
				(width 0.1)
				(type default)
			)
			(layer "B.Fab")
		)
		(fp_line
			(start -0.12065 -0.3048)
			(end -0.67945 -0.3048)
			(stroke
				(width 0.1)
				(type default)
			)
			(layer "B.Fab")
		)
		(fp_line
			(start -0.67945 0.3048)
			(end -0.120396 0.3048)
			(stroke
				(width 0.1)
				(type default)
			)
			(layer "B.Fab")
		)
		(fp_line
			(start -0.67945 -0.3048)
			(end -0.67945 0.3048)
			(stroke
				(width 0.1)
				(type default)
			)
			(layer "B.Fab")
		)
		(pad "1" smd circle
			(at 0.40005 0)
			(size 0 0)
			(layers "B.Cu" "B.Mask" "B.Paste")
			(net "P3V3_DB2000_VDD")
		)
		(pad "2" smd circle
			(at -0.40005 0)
			(size 0 0)
			(layers "B.Cu" "B.Mask" "B.Paste")
			(net "GND")
		)
	)
	(footprint ""
		(layer "B.Cu")
		(at 404.002748 -58.79846)
		(property "Reference" "R778"
			(at 0 0 0)
			(layer "B.SilkS")
			(hide yes)
			(effects
				(font
					(size 1.27 1.27)
				)
				(justify mirror)
			)
		)
		(property "Value" ""
			(at 0 0 0)
			(layer "B.Fab")
			(effects
				(font
					(size 1.27 1.27)
				)
				(justify mirror)
			)
		)
		(duplicate_pad_numbers_are_jumpers no)
		(fp_line
			(start -0.7874 -0.4064)
			(end -0.7874 0.4064)
			(stroke
				(width 0.1524)
				(type default)
			)
			(layer "B.SilkS")
		)
		(fp_line
			(start -0.7874 0.4064)
			(end 0.7874 0.4064)
			(stroke
				(width 0.1524)
				(type default)
			)
			(layer "B.SilkS")
		)
		(fp_line
			(start 0.7874 -0.4064)
			(end -0.7874 -0.4064)
			(stroke
				(width 0.1524)
				(type default)
			)
			(layer "B.SilkS")
		)
		(fp_line
			(start 0.7874 0.4064)
			(end 0.7874 -0.4064)
			(stroke
				(width 0.1524)
				(type default)
			)
			(layer "B.SilkS")
		)
		(fp_line
			(start -0.67945 -0.3048)
			(end -0.67945 0.3048)
			(stroke
				(width 0.1)
				(type default)
			)
			(layer "B.Fab")
		)
		(fp_line
			(start -0.67945 0.3048)
			(end -0.120396 0.3048)
			(stroke
				(width 0.1)
				(type default)
			)
			(layer "B.Fab")
		)
		(fp_line
			(start -0.12065 -0.3048)
			(end -0.67945 -0.3048)
			(stroke
				(width 0.1)
				(type default)
			)
			(layer "B.Fab")
		)
		(fp_line
			(start -0.12065 -0.2794)
			(end -0.12065 -0.3048)
			(stroke
				(width 0.1)
				(type default)
			)
			(layer "B.Fab")
		)
		(fp_line
			(start -0.120396 0.2794)
			(end 0.12065 0.2794)
			(stroke
				(width 0.1)
				(type default)
			)
			(layer "B.Fab")
		)
		(fp_line
			(start -0.120396 0.3048)
			(end -0.120396 0.2794)
			(stroke
				(width 0.1)
				(type default)
			)
			(layer "B.Fab")
		)
		(fp_line
			(start 0.12065 -0.305054)
			(end 0.12065 -0.2794)
			(stroke
				(width 0.1)
				(type default)
			)
			(layer "B.Fab")
		)
		(fp_line
			(start 0.12065 -0.2794)
			(end -0.12065 -0.2794)
			(stroke
				(width 0.1)
				(type default)
			)
			(layer "B.Fab")
		)
		(fp_line
			(start 0.12065 0.2794)
			(end 0.12065 0.3048)
			(stroke
				(width 0.1)
				(type default)
			)
			(layer "B.Fab")
		)
		(fp_line
			(start 0.12065 0.3048)
			(end 0.67945 0.3048)
			(stroke
				(width 0.1)
				(type default)
			)
			(layer "B.Fab")
		)
		(fp_line
			(start 0.67945 -0.305054)
			(end 0.12065 -0.305054)
			(stroke
				(width 0.1)
				(type default)
			)
			(layer "B.Fab")
		)
		(fp_line
			(start 0.67945 0.3048)
			(end 0.67945 -0.305054)
			(stroke
				(width 0.1)
				(type default)
			)
			(layer "B.Fab")
		)
		(pad "1" smd circle
			(at 0.40005 0 180)
			(size 0 0)
			(layers "B.Cu" "B.Mask" "B.Paste")
			(net "P3V3_AUX")
		)
		(pad "2" smd circle
			(at -0.40005 0 180)
			(size 0 0)
			(layers "B.Cu" "B.Mask" "B.Paste")
			(net "JTAG_DBP_BOOT_HALT_N")
		)
	)
	(footprint ""
		(layer "B.Cu")
		(at 329.170538 -186.36615 90)
		(property "Reference" "R297"
			(at 0 0 90)
			(layer "B.SilkS")
			(hide yes)
			(effects
				(font
					(size 1.27 1.27)
				)
				(justify mirror)
			)
		)
		(property "Value" ""
			(at 0 0 90)
			(layer "B.Fab")
			(effects
				(font
					(size 1.27 1.27)
				)
				(justify mirror)
			)
		)
		(duplicate_pad_numbers_are_jumpers no)
		(fp_line
			(start 0.7874 -0.4064)
			(end -0.7874 -0.4064)
			(stroke
				(width 0.1524)
				(type default)
			)
			(layer "B.SilkS")
		)
		(fp_line
			(start -0.7874 -0.4064)
			(end -0.7874 0.4064)
			(stroke
				(width 0.1524)
				(type default)
			)
			(layer "B.SilkS")
		)
		(fp_line
			(start 0.7874 0.4064)
			(end 0.7874 -0.4064)
			(stroke
				(width 0.1524)
				(type default)
			)
			(layer "B.SilkS")
		)
		(fp_line
			(start -0.7874 0.4064)
			(end 0.7874 0.4064)
			(stroke
				(width 0.1524)
				(type default)
			)
			(layer "B.SilkS")
		)
		(fp_line
			(start 0.67945 -0.305054)
			(end 0.12065 -0.305054)
			(stroke
				(width 0.1)
				(type default)
			)
			(layer "B.Fab")
		)
		(fp_line
			(start 0.12065 -0.305054)
			(end 0.12065 -0.2794)
			(stroke
				(width 0.1)
				(type default)
			)
			(layer "B.Fab")
		)
		(fp_line
			(start -0.12065 -0.3048)
			(end -0.67945 -0.3048)
			(stroke
				(width 0.1)
				(type default)
			)
			(layer "B.Fab")
		)
		(fp_line
			(start -0.67945 -0.3048)
			(end -0.67945 0.3048)
			(stroke
				(width 0.1)
				(type default)
			)
			(layer "B.Fab")
		)
		(fp_line
			(start 0.12065 -0.2794)
			(end -0.12065 -0.2794)
			(stroke
				(width 0.1)
				(type default)
			)
			(layer "B.Fab")
		)
		(fp_line
			(start -0.12065 -0.2794)
			(end -0.12065 -0.3048)
			(stroke
				(width 0.1)
				(type default)
			)
			(layer "B.Fab")
		)
		(fp_line
			(start 0.12065 0.2794)
			(end 0.12065 0.3048)
			(stroke
				(width 0.1)
				(type default)
			)
			(layer "B.Fab")
		)
		(fp_line
			(start -0.120396 0.2794)
			(end 0.12065 0.2794)
			(stroke
				(width 0.1)
				(type default)
			)
			(layer "B.Fab")
		)
		(fp_line
			(start 0.67945 0.3048)
			(end 0.67945 -0.305054)
			(stroke
				(width 0.1)
				(type default)
			)
			(layer "B.Fab")
		)
		(fp_line
			(start 0.12065 0.3048)
			(end 0.67945 0.3048)
			(stroke
				(width 0.1)
				(type default)
			)
			(layer "B.Fab")
		)
		(fp_line
			(start -0.120396 0.3048)
			(end -0.120396 0.2794)
			(stroke
				(width 0.1)
				(type default)
			)
			(layer "B.Fab")
		)
		(fp_line
			(start -0.67945 0.3048)
			(end -0.120396 0.3048)
			(stroke
				(width 0.1)
				(type default)
			)
			(layer "B.Fab")
		)
		(pad "1" smd circle
			(at 0.40005 0 270)
			(size 0 0)
			(layers "B.Cu" "B.Mask" "B.Paste")
			(net "H_CPU0_CATERR_LVC1_R_N")
		)
		(pad "2" smd circle
			(at -0.40005 0 270)
			(size 0 0)
			(layers "B.Cu" "B.Mask" "B.Paste")
			(net "H_CPU_CATERR_LVC1_R_N")
		)
	)
	(footprint ""
		(layer "B.Cu")
		(at 118.18112 -252.17628 -90)
		(property "Reference" "C351"
			(at 0 0 90)
			(layer "B.SilkS")
			(hide yes)
			(effects
				(font
					(size 1.27 1.27)
				)
				(justify mirror)
			)
		)
		(property "Value" ""
			(at 0 0 90)
			(layer "B.Fab")
			(effects
				(font
					(size 1.27 1.27)
				)
				(justify mirror)
			)
		)
		(duplicate_pad_numbers_are_jumpers no)
		(fp_line
			(start -1.524 0.762)
			(end 1.524 0.762)
			(stroke
				(width 0.1524)
				(type default)
			)
			(layer "B.SilkS")
		)
		(fp_line
			(start 1.524 0.762)
			(end 1.524 -0.762)
			(stroke
				(width 0.1524)
				(type default)
			)
			(layer "B.SilkS")
		)
		(fp_line
			(start -1.524 -0.762)
			(end -1.524 0.762)
			(stroke
				(width 0.1524)
				(type default)
			)
			(layer "B.SilkS")
		)
		(fp_line
			(start 1.524 -0.762)
			(end -1.524 -0.762)
			(stroke
				(width 0.1524)
				(type default)
			)
			(layer "B.SilkS")
		)
		(fp_line
			(start -1.1049 0.724916)
			(end -1.1049 -0.724916)
			(stroke
				(width 0.1)
				(type default)
			)
			(layer "B.Fab")
		)
		(fp_line
			(start 1.1049 0.724916)
			(end -1.1049 0.724916)
			(stroke
				(width 0.1)
				(type default)
			)
			(layer "B.Fab")
		)
		(fp_line
			(start -1.1049 -0.724916)
			(end 1.1049 -0.724916)
			(stroke
				(width 0.1)
				(type default)
			)
			(layer "B.Fab")
		)
		(fp_line
			(start 1.1049 -0.724916)
			(end 1.1049 0.724916)
			(stroke
				(width 0.1)
				(type default)
			)
			(layer "B.Fab")
		)
		(pad "1" smd rect
			(at 0.889 0 270)
			(size 1.016 1.27)
			(layers "B.Cu" "B.Mask" "B.Paste")
			(net "PVCCIN_CPU1")
		)
		(pad "2" smd rect
			(at -0.889 0 270)
			(size 1.016 1.27)
			(layers "B.Cu" "B.Mask" "B.Paste")
			(net "GND")
		)
	)
	(footprint ""
		(layer "B.Cu")
		(at 70.369684 -183.303926 90)
		(property "Reference" "R53"
			(at 0 0 90)
			(layer "B.SilkS")
			(hide yes)
			(effects
				(font
					(size 1.27 1.27)
				)
				(justify mirror)
			)
		)
		(property "Value" ""
			(at 0 0 90)
			(layer "B.Fab")
			(effects
				(font
					(size 1.27 1.27)
				)
				(justify mirror)
			)
		)
		(duplicate_pad_numbers_are_jumpers no)
		(fp_line
			(start 0.7874 -0.4064)
			(end -0.7874 -0.4064)
			(stroke
				(width 0.1524)
				(type default)
			)
			(layer "B.SilkS")
		)
		(fp_line
			(start -0.7874 -0.4064)
			(end -0.7874 0.4064)
			(stroke
				(width 0.1524)
				(type default)
			)
			(layer "B.SilkS")
		)
		(fp_line
			(start 0.7874 0.4064)
			(end 0.7874 -0.4064)
			(stroke
				(width 0.1524)
				(type default)
			)
			(layer "B.SilkS")
		)
		(fp_line
			(start -0.7874 0.4064)
			(end 0.7874 0.4064)
			(stroke
				(width 0.1524)
				(type default)
			)
			(layer "B.SilkS")
		)
		(fp_line
			(start 0.67945 -0.305054)
			(end 0.12065 -0.305054)
			(stroke
				(width 0.1)
				(type default)
			)
			(layer "B.Fab")
		)
		(fp_line
			(start 0.12065 -0.305054)
			(end 0.12065 -0.2794)
			(stroke
				(width 0.1)
				(type default)
			)
			(layer "B.Fab")
		)
		(fp_line
			(start -0.12065 -0.3048)
			(end -0.67945 -0.3048)
			(stroke
				(width 0.1)
				(type default)
			)
			(layer "B.Fab")
		)
		(fp_line
			(start -0.67945 -0.3048)
			(end -0.67945 0.3048)
			(stroke
				(width 0.1)
				(type default)
			)
			(layer "B.Fab")
		)
		(fp_line
			(start 0.12065 -0.2794)
			(end -0.12065 -0.2794)
			(stroke
				(width 0.1)
				(type default)
			)
			(layer "B.Fab")
		)
		(fp_line
			(start -0.12065 -0.2794)
			(end -0.12065 -0.3048)
			(stroke
				(width 0.1)
				(type default)
			)
			(layer "B.Fab")
		)
		(fp_line
			(start 0.12065 0.2794)
			(end 0.12065 0.3048)
			(stroke
				(width 0.1)
				(type default)
			)
			(layer "B.Fab")
		)
		(fp_line
			(start -0.120396 0.2794)
			(end 0.12065 0.2794)
			(stroke
				(width 0.1)
				(type default)
			)
			(layer "B.Fab")
		)
		(fp_line
			(start 0.67945 0.3048)
			(end 0.67945 -0.305054)
			(stroke
				(width 0.1)
				(type default)
			)
			(layer "B.Fab")
		)
		(fp_line
			(start 0.12065 0.3048)
			(end 0.67945 0.3048)
			(stroke
				(width 0.1)
				(type default)
			)
			(layer "B.Fab")
		)
		(fp_line
			(start -0.120396 0.3048)
			(end -0.120396 0.2794)
			(stroke
				(width 0.1)
				(type default)
			)
			(layer "B.Fab")
		)
		(fp_line
			(start -0.67945 0.3048)
			(end -0.120396 0.3048)
			(stroke
				(width 0.1)
				(type default)
			)
			(layer "B.Fab")
		)
		(pad "1" smd circle
			(at 0.40005 0 270)
			(size 0 0)
			(layers "B.Cu" "B.Mask" "B.Paste")
			(net "DBP_CPU1_HOOK8_MBP2_GTL_QS_R_N")
		)
		(pad "2" smd circle
			(at -0.40005 0 270)
			(size 0 0)
			(layers "B.Cu" "B.Mask" "B.Paste")
			(net "DBP_CPU_HOOK8_MBP2_GTL_QS_N")
		)
	)
	(footprint ""
		(layer "B.Cu")
		(at 182.245 -20.970748 180)
		(property "Reference" "R4513"
			(at 0 0 0)
			(layer "B.SilkS")
			(hide yes)
			(effects
				(font
					(size 1.27 1.27)
				)
				(justify mirror)
			)
		)
		(property "Value" ""
			(at 0 0 0)
			(layer "B.Fab")
			(effects
				(font
					(size 1.27 1.27)
				)
				(justify mirror)
			)
		)
		(duplicate_pad_numbers_are_jumpers no)
		(fp_line
			(start 0.7874 0.4064)
			(end 0.7874 -0.4064)
			(stroke
				(width 0.1524)
				(type default)
			)
			(layer "B.SilkS")
		)
		(fp_line
			(start 0.7874 -0.4064)
			(end -0.7874 -0.4064)
			(stroke
				(width 0.1524)
				(type default)
			)
			(layer "B.SilkS")
		)
		(fp_line
			(start -0.7874 0.4064)
			(end 0.7874 0.4064)
			(stroke
				(width 0.1524)
				(type default)
			)
			(layer "B.SilkS")
		)
		(fp_line
			(start -0.7874 -0.4064)
			(end -0.7874 0.4064)
			(stroke
				(width 0.1524)
				(type default)
			)
			(layer "B.SilkS")
		)
		(fp_line
			(start 0.67945 0.3048)
			(end 0.67945 -0.305054)
			(stroke
				(width 0.1)
				(type default)
			)
			(layer "B.Fab")
		)
		(fp_line
			(start 0.67945 -0.305054)
			(end 0.12065 -0.305054)
			(stroke
				(width 0.1)
				(type default)
			)
			(layer "B.Fab")
		)
		(fp_line
			(start 0.12065 0.3048)
			(end 0.67945 0.3048)
			(stroke
				(width 0.1)
				(type default)
			)
			(layer "B.Fab")
		)
		(fp_line
			(start 0.12065 0.2794)
			(end 0.12065 0.3048)
			(stroke
				(width 0.1)
				(type default)
			)
			(layer "B.Fab")
		)
		(fp_line
			(start 0.12065 -0.2794)
			(end -0.12065 -0.2794)
			(stroke
				(width 0.1)
				(type default)
			)
			(layer "B.Fab")
		)
		(fp_line
			(start 0.12065 -0.305054)
			(end 0.12065 -0.2794)
			(stroke
				(width 0.1)
				(type default)
			)
			(layer "B.Fab")
		)
		(fp_line
			(start -0.120396 0.3048)
			(end -0.120396 0.2794)
			(stroke
				(width 0.1)
				(type default)
			)
			(layer "B.Fab")
		)
		(fp_line
			(start -0.120396 0.2794)
			(end 0.12065 0.2794)
			(stroke
				(width 0.1)
				(type default)
			)
			(layer "B.Fab")
		)
		(fp_line
			(start -0.12065 -0.2794)
			(end -0.12065 -0.3048)
			(stroke
				(width 0.1)
				(type default)
			)
			(layer "B.Fab")
		)
		(fp_line
			(start -0.12065 -0.3048)
			(end -0.67945 -0.3048)
			(stroke
				(width 0.1)
				(type default)
			)
			(layer "B.Fab")
		)
		(fp_line
			(start -0.67945 0.3048)
			(end -0.120396 0.3048)
			(stroke
				(width 0.1)
				(type default)
			)
			(layer "B.Fab")
		)
		(fp_line
			(start -0.67945 -0.3048)
			(end -0.67945 0.3048)
			(stroke
				(width 0.1)
				(type default)
			)
			(layer "B.Fab")
		)
		(pad "1" smd circle
			(at 0.40005 0)
			(size 0 0)
			(layers "B.Cu" "B.Mask" "B.Paste")
			(net "SMB_HOST_3V3AUX_SDA")
		)
		(pad "2" smd circle
			(at -0.40005 0)
			(size 0 0)
			(layers "B.Cu" "B.Mask" "B.Paste")
			(net "SMB_HOST_3V3AUX_SDA_R5")
		)
	)
)
